(kicad_pcb
	(version 20260206)
	(generator "pcbnew")
	(generator_version "10.0")
	(general
		(thickness 1.6)
		(legacy_teardrops no)
	)
	(paper "A4")
	(title_block
		(title "01162023_DA0F0TEBIF0_F0T_Expander_BD_F_brd_V02_OCP.brd")
		(comment 1 "Grand Teton / footprint 6602 of 9728 (PEX1), pads 836-956 of 2397")
	)
	(layers
		(0 "F.Cu" signal "TOP")
		(4 "In1.Cu" signal "GND")
		(6 "In2.Cu" signal "VCC")
		(8 "In3.Cu" signal "VCC1")
		(10 "In4.Cu" signal "GND1")
		(12 "In5.Cu" signal "IN1")
		(14 "In6.Cu" signal "GND2")
		(16 "In7.Cu" signal "IN2")
		(18 "In8.Cu" signal "GND3")
		(20 "In9.Cu" signal "IN3")
		(22 "In10.Cu" signal "GND4")
		(24 "In11.Cu" signal "IN4")
		(26 "In12.Cu" signal "GND5")
		(28 "In13.Cu" signal "IN5")
		(30 "In14.Cu" signal "GND6")
		(32 "In15.Cu" signal "IN6")
		(34 "In16.Cu" signal "GND7")
		(2 "B.Cu" signal "BOTTOM")
		(9 "F.Adhes" user "F.Adhesive")
		(11 "B.Adhes" user "B.Adhesive")
		(13 "F.Paste" user "Package Geometry/Pastemask Top")
		(15 "B.Paste" user "Package Geometry/Pastemask Bottom")
		(5 "F.SilkS" user "Ref Des/Silkscreen Top")
		(7 "B.SilkS" user "Ref Des/Silkscreen Bottom")
		(1 "F.Mask" user "Board Geometry/Soldermask Top")
		(3 "B.Mask" user "Board Geometry/Soldermask Bottom")
		(17 "Dwgs.User" user "User.Drawings")
		(19 "Cmts.User" user "User.Comments")
		(21 "Eco1.User" user "User.Eco1")
		(23 "Eco2.User" user "User.Eco2")
		(25 "Edge.Cuts" user "Board Geometry/Outline")
		(27 "Margin" user)
		(31 "F.CrtYd" user "Package Geometry/Place Bound Top")
		(29 "B.CrtYd" user "Package Geometry/Place Bound Bottom")
		(35 "F.Fab" user "Ref Des/Assembly Top")
		(33 "B.Fab" user "Ref Des/Assembly Bottom")
	)
	(footprint ""
		(layer "F.Cu")
		(at 175.749966 -295.89984)
		(property "Reference" "PEX1"
			(at -3.353562 35.593274 0)
			(unlocked yes)
			(layer "F.SilkS")
			(effects
				(font
					(size 2.032 1.524)
					(thickness 0.1524)
				)
				(justify left)
			)
		)
		(property "Value" ""
			(at 0 0 0)
			(layer "F.Fab")
			(effects
				(font
					(size 1.27 1.27)
				)
			)
		)
		(duplicate_pad_numbers_are_jumpers no)
		(pad "AU5" smd circle
			(at -18.999962 11.400028)
			(size 0.4572 0.4572)
			(layers "F.Cu" "F.Mask" "F.Paste")
			(net "GND")
		)
		(pad "AU6" smd circle
			(at -18.050002 11.400028)
			(size 0.4572 0.4572)
			(layers "F.Cu" "F.Mask" "F.Paste")
			(net "Net_1678")
		)
		(pad "AU7" smd circle
			(at -17.100042 11.400028)
			(size 0.4572 0.4572)
			(layers "F.Cu" "F.Mask" "F.Paste")
			(net "Net_1643")
		)
		(pad "AU8" smd circle
			(at -16.150082 11.400028)
			(size 0.4572 0.4572)
			(layers "F.Cu" "F.Mask" "F.Paste")
			(net "GND")
		)
		(pad "AU9" smd circle
			(at -15.200122 11.400028)
			(size 0.4572 0.4572)
			(layers "F.Cu" "F.Mask" "F.Paste")
			(net "GND")
		)
		(pad "AU10" smd circle
			(at -14.249908 11.400028)
			(size 0.4572 0.4572)
			(layers "F.Cu" "F.Mask" "F.Paste")
			(net "GND")
		)
		(pad "AU11" smd circle
			(at -13.299948 11.400028)
			(size 0.4572 0.4572)
			(layers "F.Cu" "F.Mask" "F.Paste")
			(net "GND")
		)
		(pad "AU12" smd circle
			(at -12.349988 11.400028)
			(size 0.4572 0.4572)
			(layers "F.Cu" "F.Mask" "F.Paste")
			(net "GND")
		)
		(pad "AU13" smd circle
			(at -11.400028 11.400028)
			(size 0.4572 0.4572)
			(layers "F.Cu" "F.Mask" "F.Paste")
			(net "GND")
		)
		(pad "AU14" smd circle
			(at -10.450068 11.400028)
			(size 0.4572 0.4572)
			(layers "F.Cu" "F.Mask" "F.Paste")
			(net "GND")
		)
		(pad "AU15" smd circle
			(at -9.500108 11.400028)
			(size 0.4572 0.4572)
			(layers "F.Cu" "F.Mask" "F.Paste")
			(net "GND")
		)
		(pad "AU16" smd circle
			(at -8.549894 11.400028)
			(size 0.4572 0.4572)
			(layers "F.Cu" "F.Mask" "F.Paste")
			(net "GND")
		)
		(pad "AU17" smd circle
			(at -7.599934 11.400028)
			(size 0.4572 0.4572)
			(layers "F.Cu" "F.Mask" "F.Paste")
			(net "GND")
		)
		(pad "AU18" smd circle
			(at -6.649974 11.400028)
			(size 0.4572 0.4572)
			(layers "F.Cu" "F.Mask" "F.Paste")
			(net "GND")
		)
		(pad "AU19" smd circle
			(at -5.700014 11.400028)
			(size 0.4572 0.4572)
			(layers "F.Cu" "F.Mask" "F.Paste")
			(net "GND")
		)
		(pad "AU20" smd circle
			(at -4.750054 11.400028)
			(size 0.4572 0.4572)
			(layers "F.Cu" "F.Mask" "F.Paste")
			(net "GND")
		)
		(pad "AU21" smd circle
			(at -3.800094 11.400028)
			(size 0.4572 0.4572)
			(layers "F.Cu" "F.Mask" "F.Paste")
			(net "GND")
		)
		(pad "AU22" smd circle
			(at -2.84988 11.400028)
			(size 0.4572 0.4572)
			(layers "F.Cu" "F.Mask" "F.Paste")
			(net "GND")
		)
		(pad "AU23" smd circle
			(at -1.89992 11.400028)
			(size 0.4572 0.4572)
			(layers "F.Cu" "F.Mask" "F.Paste")
			(net "GND")
		)
		(pad "AU24" smd circle
			(at -0.94996 11.400028)
			(size 0.4572 0.4572)
			(layers "F.Cu" "F.Mask" "F.Paste")
			(net "GND")
		)
		(pad "AU25" smd circle
			(at 0 11.400028)
			(size 0.4572 0.4572)
			(layers "F.Cu" "F.Mask" "F.Paste")
			(net "GND")
		)
		(pad "AU26" smd circle
			(at 0.94996 11.400028)
			(size 0.4572 0.4572)
			(layers "F.Cu" "F.Mask" "F.Paste")
			(net "GND")
		)
		(pad "AU27" smd circle
			(at 1.89992 11.400028)
			(size 0.4572 0.4572)
			(layers "F.Cu" "F.Mask" "F.Paste")
			(net "GND")
		)
		(pad "AU28" smd circle
			(at 2.84988 11.400028)
			(size 0.4572 0.4572)
			(layers "F.Cu" "F.Mask" "F.Paste")
			(net "GND")
		)
		(pad "AU29" smd circle
			(at 3.800094 11.400028)
			(size 0.4572 0.4572)
			(layers "F.Cu" "F.Mask" "F.Paste")
			(net "GND")
		)
		(pad "AU30" smd circle
			(at 4.750054 11.400028)
			(size 0.4572 0.4572)
			(layers "F.Cu" "F.Mask" "F.Paste")
			(net "GND")
		)
		(pad "AU31" smd circle
			(at 5.700014 11.400028)
			(size 0.4572 0.4572)
			(layers "F.Cu" "F.Mask" "F.Paste")
			(net "GND")
		)
		(pad "AU32" smd circle
			(at 6.649974 11.400028)
			(size 0.4572 0.4572)
			(layers "F.Cu" "F.Mask" "F.Paste")
			(net "GND")
		)
		(pad "AU33" smd circle
			(at 7.599934 11.400028)
			(size 0.4572 0.4572)
			(layers "F.Cu" "F.Mask" "F.Paste")
			(net "GND")
		)
		(pad "AU34" smd circle
			(at 8.549894 11.400028)
			(size 0.4572 0.4572)
			(layers "F.Cu" "F.Mask" "F.Paste")
			(net "GND")
		)
		(pad "AU35" smd circle
			(at 9.500108 11.400028)
			(size 0.4572 0.4572)
			(layers "F.Cu" "F.Mask" "F.Paste")
			(net "GND")
		)
		(pad "AU36" smd circle
			(at 10.450068 11.400028)
			(size 0.4572 0.4572)
			(layers "F.Cu" "F.Mask" "F.Paste")
			(net "GND")
		)
		(pad "AU37" smd circle
			(at 11.400028 11.400028)
			(size 0.4572 0.4572)
			(layers "F.Cu" "F.Mask" "F.Paste")
			(net "GND")
		)
		(pad "AU38" smd circle
			(at 12.349988 11.400028)
			(size 0.4572 0.4572)
			(layers "F.Cu" "F.Mask" "F.Paste")
			(net "Net_5268")
		)
		(pad "AU39" smd circle
			(at 13.299948 11.400028)
			(size 0.4572 0.4572)
			(layers "F.Cu" "F.Mask" "F.Paste")
			(net "Net_5240")
		)
		(pad "AU40" smd circle
			(at 14.249908 11.400028)
			(size 0.4572 0.4572)
			(layers "F.Cu" "F.Mask" "F.Paste")
			(net "GND")
		)
		(pad "AU41" smd circle
			(at 15.200122 11.400028)
			(size 0.4572 0.4572)
			(layers "F.Cu" "F.Mask" "F.Paste")
			(net "GND")
		)
		(pad "AU42" smd circle
			(at 16.150082 11.400028)
			(size 0.4572 0.4572)
			(layers "F.Cu" "F.Mask" "F.Paste")
			(net "GND")
		)
		(pad "AU43" smd circle
			(at 17.100042 11.400028)
			(size 0.4572 0.4572)
			(layers "F.Cu" "F.Mask" "F.Paste")
			(net "P5E_PEX1_STN0_TX_DP<4>")
		)
		(pad "AU44" smd circle
			(at 18.050002 11.400028)
			(size 0.4572 0.4572)
			(layers "F.Cu" "F.Mask" "F.Paste")
			(net "P5E_PEX1_STN0_TX_DN<4>")
		)
		(pad "AU45" smd circle
			(at 18.999962 11.400028)
			(size 0.4572 0.4572)
			(layers "F.Cu" "F.Mask" "F.Paste")
			(net "GND")
		)
		(pad "AU46" smd circle
			(at 19.949922 11.400028)
			(size 0.4572 0.4572)
			(layers "F.Cu" "F.Mask" "F.Paste")
			(net "P5E_PEX1_STN0_RX_DP<4>")
		)
		(pad "AU47" smd circle
			(at 20.899882 11.400028)
			(size 0.4572 0.4572)
			(layers "F.Cu" "F.Mask" "F.Paste")
			(net "P5E_PEX1_STN0_RX_DN<4>")
		)
		(pad "AU48" smd circle
			(at 21.850096 11.400028)
			(size 0.4572 0.4572)
			(layers "F.Cu" "F.Mask" "F.Paste")
			(net "GND")
		)
		(pad "AU49" smd circle
			(at 22.800056 11.400028)
			(size 0.4572 0.4572)
			(layers "F.Cu" "F.Mask" "F.Paste")
			(net "GND")
		)
		(pad "AV1" smd circle
			(at -22.800056 12.349988)
			(size 0.4572 0.4572)
			(layers "F.Cu" "F.Mask" "F.Paste")
			(net "Net_1411")
		)
		(pad "AV2" smd circle
			(at -21.850096 12.349988)
			(size 0.4572 0.4572)
			(layers "F.Cu" "F.Mask" "F.Paste")
			(net "Net_1398")
		)
		(pad "AV3" smd circle
			(at -20.899882 12.349988)
			(size 0.4572 0.4572)
			(layers "F.Cu" "F.Mask" "F.Paste")
			(net "GND")
		)
		(pad "AV4" smd circle
			(at -19.949922 12.349988)
			(size 0.4572 0.4572)
			(layers "F.Cu" "F.Mask" "F.Paste")
			(net "GND")
		)
		(pad "AV5" smd circle
			(at -18.999962 12.349988)
			(size 0.4572 0.4572)
			(layers "F.Cu" "F.Mask" "F.Paste")
			(net "GND")
		)
		(pad "AV6" smd circle
			(at -18.050002 12.349988)
			(size 0.4572 0.4572)
			(layers "F.Cu" "F.Mask" "F.Paste")
			(net "GND")
		)
		(pad "AV7" smd circle
			(at -17.100042 12.349988)
			(size 0.4572 0.4572)
			(layers "F.Cu" "F.Mask" "F.Paste")
			(net "GND")
		)
		(pad "AV8" smd circle
			(at -16.150082 12.349988)
			(size 0.4572 0.4572)
			(layers "F.Cu" "F.Mask" "F.Paste")
			(net "Net_1690")
		)
		(pad "AV9" smd circle
			(at -15.200122 12.349988)
			(size 0.4572 0.4572)
			(layers "F.Cu" "F.Mask" "F.Paste")
			(net "Net_1666")
		)
		(pad "AV10" smd circle
			(at -14.249908 12.349988)
			(size 0.4572 0.4572)
			(layers "F.Cu" "F.Mask" "F.Paste")
			(net "GND")
		)
		(pad "AV11" smd circle
			(at -13.299948 12.349988)
			(size 0.4572 0.4572)
			(layers "F.Cu" "F.Mask" "F.Paste")
			(net "GND")
		)
		(pad "AV12" smd circle
			(at -12.349988 12.349988)
			(size 0.4572 0.4572)
			(layers "F.Cu" "F.Mask" "F.Paste")
			(net "Net_5258")
		)
		(pad "AV13" smd circle
			(at -11.400028 12.349988)
			(size 0.4572 0.4572)
			(layers "F.Cu" "F.Mask" "F.Paste")
			(net "Net_5259")
		)
		(pad "AV14" smd circle
			(at -10.450068 12.349988)
			(size 0.4572 0.4572)
			(layers "F.Cu" "F.Mask" "F.Paste")
			(net "Net_5250")
		)
		(pad "AV15" smd circle
			(at -9.500108 12.349988)
			(size 0.4572 0.4572)
			(layers "F.Cu" "F.Mask" "F.Paste")
			(net "Net_5244")
		)
		(pad "AV16" smd circle
			(at -8.549894 12.349988)
			(size 0.4572 0.4572)
			(layers "F.Cu" "F.Mask" "F.Paste")
			(net "Net_5253")
		)
		(pad "AV17" smd circle
			(at -7.599934 12.349988)
			(size 0.4572 0.4572)
			(layers "F.Cu" "F.Mask" "F.Paste")
			(net "Net_5254")
		)
		(pad "AV18" smd circle
			(at -6.649974 12.349988)
			(size 0.4572 0.4572)
			(layers "F.Cu" "F.Mask" "F.Paste")
			(net "Net_5249")
		)
		(pad "AV19" smd circle
			(at -5.700014 12.349988)
			(size 0.4572 0.4572)
			(layers "F.Cu" "F.Mask" "F.Paste")
			(net "Net_5245")
		)
		(pad "AV20" smd circle
			(at -4.750054 12.349988)
			(size 0.4572 0.4572)
			(layers "F.Cu" "F.Mask" "F.Paste")
			(net "GND")
		)
		(pad "AV21" smd circle
			(at -3.800094 12.349988)
			(size 0.4572 0.4572)
			(layers "F.Cu" "F.Mask" "F.Paste")
			(net "Net_5284")
		)
		(pad "AV22" smd circle
			(at -2.84988 12.349988)
			(size 0.4572 0.4572)
			(layers "F.Cu" "F.Mask" "F.Paste")
			(net "Net_5285")
		)
		(pad "AV23" smd circle
			(at -1.89992 12.349988)
			(size 0.4572 0.4572)
			(layers "F.Cu" "F.Mask" "F.Paste")
			(net "Net_5287")
		)
		(pad "AV24" smd circle
			(at -0.94996 12.349988)
			(size 0.4572 0.4572)
			(layers "F.Cu" "F.Mask" "F.Paste")
			(net "GND")
		)
		(pad "AV25" smd circle
			(at 0 12.349988)
			(size 0.4572 0.4572)
			(layers "F.Cu" "F.Mask" "F.Paste")
			(net "PEX1_MODE_SEL2")
		)
		(pad "AV26" smd circle
			(at 0.94996 12.349988)
			(size 0.4572 0.4572)
			(layers "F.Cu" "F.Mask" "F.Paste")
			(net "PEX1_MODE_SEL7")
		)
		(pad "AV27" smd circle
			(at 1.89992 12.349988)
			(size 0.4572 0.4572)
			(layers "F.Cu" "F.Mask" "F.Paste")
			(net "PEX1_MODE_SEL3")
		)
		(pad "AV28" smd circle
			(at 2.84988 12.349988)
			(size 0.4572 0.4572)
			(layers "F.Cu" "F.Mask" "F.Paste")
			(net "PEX1_MODE_SEL9")
		)
		(pad "AV29" smd circle
			(at 3.800094 12.349988)
			(size 0.4572 0.4572)
			(layers "F.Cu" "F.Mask" "F.Paste")
			(net "PEX1_PCA9555_INT_R_N")
		)
		(pad "AV30" smd circle
			(at 4.750054 12.349988)
			(size 0.4572 0.4572)
			(layers "F.Cu" "F.Mask" "F.Paste")
			(net "PEX1_SYS_ERR_N")
		)
		(pad "AV31" smd circle
			(at 5.700014 12.349988)
			(size 0.4572 0.4572)
			(layers "F.Cu" "F.Mask" "F.Paste")
			(net "PEX1_MODE_SEL6")
		)
		(pad "AV32" smd circle
			(at 6.649974 12.349988)
			(size 0.4572 0.4572)
			(layers "F.Cu" "F.Mask" "F.Paste")
			(net "PEX1_MODE_SEL10")
		)
		(pad "AV33" smd circle
			(at 7.599934 12.349988)
			(size 0.4572 0.4572)
			(layers "F.Cu" "F.Mask" "F.Paste")
			(net "Net_5262")
		)
		(pad "AV34" smd circle
			(at 8.549894 12.349988)
			(size 0.4572 0.4572)
			(layers "F.Cu" "F.Mask" "F.Paste")
			(net "Net_5235")
		)
		(pad "AV35" smd circle
			(at 9.500108 12.349988)
			(size 0.4572 0.4572)
			(layers "F.Cu" "F.Mask" "F.Paste")
			(net "Net_5264")
		)
		(pad "AV36" smd circle
			(at 10.450068 12.349988)
			(size 0.4572 0.4572)
			(layers "F.Cu" "F.Mask" "F.Paste")
			(net "Net_5241")
		)
		(pad "AV37" smd circle
			(at 11.400028 12.349988)
			(size 0.4572 0.4572)
			(layers "F.Cu" "F.Mask" "F.Paste")
			(net "Net_5266")
		)
		(pad "AV38" smd circle
			(at 12.349988 12.349988)
			(size 0.4572 0.4572)
			(layers "F.Cu" "F.Mask" "F.Paste")
			(net "Net_5265")
		)
		(pad "AV39" smd circle
			(at 13.299948 12.349988)
			(size 0.4572 0.4572)
			(layers "F.Cu" "F.Mask" "F.Paste")
			(net "Net_5257")
		)
		(pad "AV40" smd circle
			(at 14.249908 12.349988)
			(size 0.4572 0.4572)
			(layers "F.Cu" "F.Mask" "F.Paste")
			(net "GND")
		)
		(pad "AV41" smd circle
			(at 15.200122 12.349988)
			(size 0.4572 0.4572)
			(layers "F.Cu" "F.Mask" "F.Paste")
			(net "P5E_PEX1_STN0_TX_DP<5>")
		)
		(pad "AV42" smd circle
			(at 16.150082 12.349988)
			(size 0.4572 0.4572)
			(layers "F.Cu" "F.Mask" "F.Paste")
			(net "P5E_PEX1_STN0_TX_DN<5>")
		)
		(pad "AV43" smd circle
			(at 17.100042 12.349988)
			(size 0.4572 0.4572)
			(layers "F.Cu" "F.Mask" "F.Paste")
			(net "GND")
		)
		(pad "AV44" smd circle
			(at 18.050002 12.349988)
			(size 0.4572 0.4572)
			(layers "F.Cu" "F.Mask" "F.Paste")
			(net "GND")
		)
		(pad "AV45" smd circle
			(at 18.999962 12.349988)
			(size 0.4572 0.4572)
			(layers "F.Cu" "F.Mask" "F.Paste")
			(net "GND")
		)
		(pad "AV46" smd circle
			(at 19.949922 12.349988)
			(size 0.4572 0.4572)
			(layers "F.Cu" "F.Mask" "F.Paste")
			(net "GND")
		)
		(pad "AV47" smd circle
			(at 20.899882 12.349988)
			(size 0.4572 0.4572)
			(layers "F.Cu" "F.Mask" "F.Paste")
			(net "GND")
		)
		(pad "AV48" smd circle
			(at 21.850096 12.349988)
			(size 0.4572 0.4572)
			(layers "F.Cu" "F.Mask" "F.Paste")
			(net "P5E_PEX1_STN0_RX_DP<5>")
		)
		(pad "AV49" smd circle
			(at 22.800056 12.349988)
			(size 0.4572 0.4572)
			(layers "F.Cu" "F.Mask" "F.Paste")
			(net "P5E_PEX1_STN0_RX_DN<5>")
		)
		(pad "AW1" smd circle
			(at -22.800056 13.299948)
			(size 0.4572 0.4572)
			(layers "F.Cu" "F.Mask" "F.Paste")
			(net "GND")
		)
		(pad "AW2" smd circle
			(at -21.850096 13.299948)
			(size 0.4572 0.4572)
			(layers "F.Cu" "F.Mask" "F.Paste")
			(net "GND")
		)
		(pad "AW3" smd circle
			(at -20.899882 13.299948)
			(size 0.4572 0.4572)
			(layers "F.Cu" "F.Mask" "F.Paste")
			(net "Net_1363")
		)
		(pad "AW4" smd circle
			(at -19.949922 13.299948)
			(size 0.4572 0.4572)
			(layers "F.Cu" "F.Mask" "F.Paste")
			(net "Net_1706")
		)
		(pad "AW5" smd circle
			(at -18.999962 13.299948)
			(size 0.4572 0.4572)
			(layers "F.Cu" "F.Mask" "F.Paste")
			(net "GND")
		)
		(pad "AW6" smd circle
			(at -18.050002 13.299948)
			(size 0.4572 0.4572)
			(layers "F.Cu" "F.Mask" "F.Paste")
			(net "Net_1668")
		)
		(pad "AW7" smd circle
			(at -17.100042 13.299948)
			(size 0.4572 0.4572)
			(layers "F.Cu" "F.Mask" "F.Paste")
			(net "Net_1688")
		)
		(pad "AW8" smd circle
			(at -16.150082 13.299948)
			(size 0.4572 0.4572)
			(layers "F.Cu" "F.Mask" "F.Paste")
			(net "GND")
		)
		(pad "AW9" smd circle
			(at -15.200122 13.299948)
			(size 0.4572 0.4572)
			(layers "F.Cu" "F.Mask" "F.Paste")
			(net "GND")
		)
		(pad "AW10" smd circle
			(at -14.249908 13.299948)
			(size 0.4572 0.4572)
			(layers "F.Cu" "F.Mask" "F.Paste")
			(net "GND")
		)
		(pad "AW11" smd circle
			(at -13.299948 13.299948)
			(size 0.4572 0.4572)
			(layers "F.Cu" "F.Mask" "F.Paste")
			(net "GND")
		)
		(pad "AW12" smd circle
			(at -12.349988 13.299948)
			(size 0.4572 0.4572)
			(layers "F.Cu" "F.Mask" "F.Paste")
			(net "Net_5256")
		)
		(pad "AW13" smd circle
			(at -11.400028 13.299948)
			(size 0.4572 0.4572)
			(layers "F.Cu" "F.Mask" "F.Paste")
			(net "Net_5252")
		)
		(pad "AW14" smd circle
			(at -10.450068 13.299948)
			(size 0.4572 0.4572)
			(layers "F.Cu" "F.Mask" "F.Paste")
			(net "Net_5248")
		)
		(pad "AW15" smd circle
			(at -9.500108 13.299948)
			(size 0.4572 0.4572)
			(layers "F.Cu" "F.Mask" "F.Paste")
			(net "Net_5243")
		)
		(pad "AW16" smd circle
			(at -8.549894 13.299948)
			(size 0.4572 0.4572)
			(layers "F.Cu" "F.Mask" "F.Paste")
			(net "Net_5255")
		)
		(pad "AW17" smd circle
			(at -7.599934 13.299948)
			(size 0.4572 0.4572)
			(layers "F.Cu" "F.Mask" "F.Paste")
			(net "Net_5251")
		)
		(pad "AW18" smd circle
			(at -6.649974 13.299948)
			(size 0.4572 0.4572)
			(layers "F.Cu" "F.Mask" "F.Paste")
			(net "Net_5247")
		)
		(pad "AW19" smd circle
			(at -5.700014 13.299948)
			(size 0.4572 0.4572)
			(layers "F.Cu" "F.Mask" "F.Paste")
			(net "Net_5242")
		)
		(pad "AW20" smd circle
			(at -4.750054 13.299948)
			(size 0.4572 0.4572)
			(layers "F.Cu" "F.Mask" "F.Paste")
			(net "GND")
		)
		(pad "AW21" smd circle
			(at -3.800094 13.299948)
			(size 0.4572 0.4572)
			(layers "F.Cu" "F.Mask" "F.Paste")
			(net "Net_5276")
		)
		(pad "AW22" smd circle
			(at -2.84988 13.299948)
			(size 0.4572 0.4572)
			(layers "F.Cu" "F.Mask" "F.Paste")
			(net "Net_5286")
		)
		(pad "AW23" smd circle
			(at -1.89992 13.299948)
			(size 0.4572 0.4572)
			(layers "F.Cu" "F.Mask" "F.Paste")
			(net "Net_5275")
		)
		(pad "AW24" smd circle
			(at -0.94996 13.299948)
			(size 0.4572 0.4572)
			(layers "F.Cu" "F.Mask" "F.Paste")
			(net "GND")
		)
		(pad "AW25" smd circle
			(at 0 13.299948)
			(size 0.4572 0.4572)
			(layers "F.Cu" "F.Mask" "F.Paste")
			(net "PEX1_MODE_SEL5")
		)
		(pad "AW26" smd circle
			(at 0.94996 13.299948)
			(size 0.4572 0.4572)
			(layers "F.Cu" "F.Mask" "F.Paste")
			(net "PEX1_DBG_MODE3")
		)
		(pad "AW27" smd circle
			(at 1.89992 13.299948)
			(size 0.4572 0.4572)
			(layers "F.Cu" "F.Mask" "F.Paste")
			(net "PEX1_MODE_SEL0")
		)
	)
)
